(kicad_pcb
	(version 20241229)
	(generator "pcbnew")
	(generator_version "9.0")
	(general
		(thickness 1.599998)
		(legacy_teardrops no)
	)
	(paper "A4")
	(title_block
		(title "Artix - Datacenter Secure Control Module (DC-SCM)")
		(date "2024-11-06")
		(rev "1.1.3")
		(comment 9 "footprints 135-140 of 544")
	)
	(layers
		(0 "F.Cu" signal)
		(4 "In1.Cu" signal)
		(6 "In2.Cu" signal)
		(8 "In3.Cu" signal)
		(10 "In4.Cu" signal)
		(12 "In5.Cu" signal)
		(14 "In6.Cu" signal)
		(2 "B.Cu" signal)
		(9 "F.Adhes" user "F.Adhesive")
		(11 "B.Adhes" user "B.Adhesive")
		(13 "F.Paste" user)
		(15 "B.Paste" user)
		(5 "F.SilkS" user "F.Silkscreen")
		(7 "B.SilkS" user "B.Silkscreen")
		(1 "F.Mask" user)
		(3 "B.Mask" user)
		(17 "Dwgs.User" user "User.Drawings")
		(19 "Cmts.User" user "User.Comments")
		(21 "Eco1.User" user "User.Eco1")
		(23 "Eco2.User" user "User.Eco2")
		(25 "Edge.Cuts" user)
		(27 "Margin" user)
		(31 "F.CrtYd" user "F.Courtyard")
		(29 "B.CrtYd" user "B.Courtyard")
		(35 "F.Fab" user)
		(33 "B.Fab" user)
	)
	(footprint "antmicro-footprints:R_0402_1005Metric"
		(layer "F.Cu")
		(at 76.74 162.06 -90)
		(descr "Resistor SMD 0402")
		(tags "resistor SMD 0402")
		(property "Reference" "R47"
			(at -2.16 -8.36 90)
			(layer "F.SilkS")
			(effects
				(font
					(size 0.7 0.7)
					(thickness 0.15)
				)
				(justify right bottom)
			)
		)
		(property "Value" "R_357k_0402"
			(at 0 1.4 90)
			(layer "F.Fab")
			(effects
				(font
					(size 0.7 0.7)
					(thickness 0.15)
				)
				(justify right bottom)
			)
		)
		(property "Datasheet" "https://www.bourns.com/docs/product-datasheets/cr.pdf"
			(at 0 0 270)
			(layer "F.Fab")
			(hide yes)
			(effects
				(font
					(size 1.27 1.27)
					(thickness 0.15)
				)
			)
		)
		(property "Description" "SMD Chip Resistor"
			(at 0 0 270)
			(layer "F.Fab")
			(hide yes)
			(effects
				(font
					(size 1.27 1.27)
					(thickness 0.15)
				)
			)
		)
		(property "Author" "Antmicro"
			(at -85.32 238.8 0)
			(layer "F.Fab")
			(hide yes)
			(effects
				(font
					(size 1 1)
					(thickness 0.15)
				)
			)
		)
		(property "License" "Apache-2.0"
			(at -85.32 238.8 0)
			(layer "F.Fab")
			(hide yes)
			(effects
				(font
					(size 1 1)
					(thickness 0.15)
				)
			)
		)
		(property "MPN" "CR0402-FX-3573GLF"
			(at -85.32 238.8 0)
			(layer "F.Fab")
			(hide yes)
			(effects
				(font
					(size 1 1)
					(thickness 0.15)
				)
			)
		)
		(property "Manufacturer" "Bourns"
			(at -85.32 238.8 0)
			(layer "F.Fab")
			(hide yes)
			(effects
				(font
					(size 1 1)
					(thickness 0.15)
				)
			)
		)
		(property "Tolerance" "1%"
			(at -85.32 238.8 0)
			(layer "F.Fab")
			(hide yes)
			(effects
				(font
					(size 1 1)
					(thickness 0.15)
				)
			)
		)
		(property "Val" "357k"
			(at -85.32 238.8 0)
			(layer "F.Fab")
			(hide yes)
			(effects
				(font
					(size 1 1)
					(thickness 0.15)
				)
			)
		)
		(sheetname "/Interfaces/")
		(sheetfile "interfaces.kicad_sch")
		(attr smd)
		(fp_rect
			(start -0.925 -0.47)
			(end 0.925 0.47)
			(stroke
				(width 0.05)
				(type default)
			)
			(fill no)
			(layer "F.CrtYd")
		)
		(fp_rect
			(start -0.5 -0.25)
			(end 0.5 0.25)
			(stroke
				(width 0.15)
				(type solid)
			)
			(fill no)
			(layer "F.Fab")
		)
		(pad "1" smd roundrect
			(at -0.48 0 270)
			(size 0.59 0.64)
			(layers "F.Cu" "F.Mask" "F.Paste")
			(roundrect_rratio 0.25)
			(net 2 "VCC3V3")
			(pintype "passive")
		)
		(pad "2" smd roundrect
			(at 0.48 0 270)
			(size 0.59 0.64)
			(layers "F.Cu" "F.Mask" "F.Paste")
			(roundrect_rratio 0.25)
			(net 170 "I3C[1]_SDA_3V3")
			(pintype "passive")
		)
	)
	(footprint "antmicro-footprints:R_0402_1005Metric"
		(layer "F.Cu")
		(at 105.275 160.275)
		(descr "Resistor SMD 0402")
		(tags "resistor SMD 0402")
		(property "Reference" "R113"
			(at 0.725 0.425 0)
			(layer "F.SilkS")
			(effects
				(font
					(size 0.7 0.7)
					(thickness 0.15)
				)
				(justify left bottom)
			)
		)
		(property "Value" "R_10k_0402"
			(at 0 1.4 0)
			(layer "F.Fab")
			(effects
				(font
					(size 0.7 0.7)
					(thickness 0.15)
				)
				(justify left bottom)
			)
		)
		(property "Datasheet" "https://www.bourns.com/docs/product-datasheets/cr.pdf"
			(at 0 0 0)
			(layer "F.Fab")
			(hide yes)
			(effects
				(font
					(size 1.27 1.27)
					(thickness 0.15)
				)
			)
		)
		(property "Description" "SMD Chip Resistor, 10 kohm, ± 1%, 62.5 mW, 0402 [1005 Metric], Thick Film, General Purpose"
			(at 0 0 0)
			(layer "F.Fab")
			(hide yes)
			(effects
				(font
					(size 1.27 1.27)
					(thickness 0.15)
				)
			)
		)
		(property "Author" "Antmicro"
			(at 0 0 0)
			(layer "F.Fab")
			(hide yes)
			(effects
				(font
					(size 1 1)
					(thickness 0.15)
				)
			)
		)
		(property "License" "Apache-2.0"
			(at 0 0 0)
			(layer "F.Fab")
			(hide yes)
			(effects
				(font
					(size 1 1)
					(thickness 0.15)
				)
			)
		)
		(property "MPN" "CR0402-FX-1002GLF"
			(at 0 0 0)
			(layer "F.Fab")
			(hide yes)
			(effects
				(font
					(size 1 1)
					(thickness 0.15)
				)
			)
		)
		(property "Manufacturer" "Bourns"
			(at 0 0 0)
			(layer "F.Fab")
			(hide yes)
			(effects
				(font
					(size 1 1)
					(thickness 0.15)
				)
			)
		)
		(property "Tolerance" "1%"
			(at 0 0 0)
			(layer "F.Fab")
			(hide yes)
			(effects
				(font
					(size 1 1)
					(thickness 0.15)
				)
			)
		)
		(property "Val" "10k"
			(at 0 0 0)
			(layer "F.Fab")
			(hide yes)
			(effects
				(font
					(size 1 1)
					(thickness 0.15)
				)
			)
		)
		(sheetname "/DDR3/")
		(sheetfile "ddr3.kicad_sch")
		(attr smd)
		(fp_rect
			(start -0.925 -0.47)
			(end 0.925 0.47)
			(stroke
				(width 0.05)
				(type default)
			)
			(fill no)
			(layer "F.CrtYd")
		)
		(fp_rect
			(start -0.5 -0.25)
			(end 0.5 0.25)
			(stroke
				(width 0.15)
				(type solid)
			)
			(fill no)
			(layer "F.Fab")
		)
		(pad "1" smd roundrect
			(at -0.48 0)
			(size 0.59 0.64)
			(layers "F.Cu" "F.Mask" "F.Paste")
			(roundrect_rratio 0.25)
			(net 341 "Net-(U8-EN)")
			(pintype "passive")
		)
		(pad "2" smd roundrect
			(at 0.48 0)
			(size 0.59 0.64)
			(layers "F.Cu" "F.Mask" "F.Paste")
			(roundrect_rratio 0.25)
			(net 2 "VCC3V3")
			(pintype "passive")
		)
	)
	(footprint "antmicro-footprints:C_0402_1005Metric"
		(layer "F.Cu")
		(at 124.005 168.181 -90)
		(descr "Capacitor SMD 0402")
		(tags "capacitor SMD 0402")
		(property "Reference" "C29"
			(at 0.819 -0.404 90)
			(layer "F.SilkS")
			(effects
				(font
					(size 0.7 0.7)
					(thickness 0.15)
				)
				(justify right bottom)
			)
		)
		(property "Value" "C_100n_6V3_0402"
			(at 0 1.4 90)
			(layer "F.Fab")
			(effects
				(font
					(size 0.7 0.7)
					(thickness 0.15)
				)
				(justify right bottom)
			)
		)
		(property "Datasheet" "https://www.passivecomponent.com/wp-content/uploads/datasheet/WTC_MLCC_General_Purpose.pdf"
			(at 0 0 270)
			(layer "F.Fab")
			(hide yes)
			(effects
				(font
					(size 1.27 1.27)
					(thickness 0.15)
				)
			)
		)
		(property "Description" "SMT Multilayer Ceramic Capacitor, 0.1 µF, 6.3 V, 0402 [1005 Metric], ± 10%, X5R, Walsin MLCC"
			(at 0 0 270)
			(layer "F.Fab")
			(hide yes)
			(effects
				(font
					(size 1.27 1.27)
					(thickness 0.15)
				)
			)
		)
		(property "Author" "Antmicro"
			(at -44.176 292.186 0)
			(layer "F.Fab")
			(hide yes)
			(effects
				(font
					(size 1 1)
					(thickness 0.15)
				)
			)
		)
		(property "Dielectric" ""
			(at -44.176 292.186 0)
			(layer "F.Fab")
			(hide yes)
			(effects
				(font
					(size 1 1)
					(thickness 0.15)
				)
			)
		)
		(property "License" "Apache-2.0"
			(at -44.176 292.186 0)
			(layer "F.Fab")
			(hide yes)
			(effects
				(font
					(size 1 1)
					(thickness 0.15)
				)
			)
		)
		(property "MPN" "0402X104K6R3CT"
			(at -44.176 292.186 0)
			(layer "F.Fab")
			(hide yes)
			(effects
				(font
					(size 1 1)
					(thickness 0.15)
				)
			)
		)
		(property "Manufacturer" "Walsin"
			(at -44.176 292.186 0)
			(layer "F.Fab")
			(hide yes)
			(effects
				(font
					(size 1 1)
					(thickness 0.15)
				)
			)
		)
		(property "Public" "False"
			(at -44.176 292.186 0)
			(layer "F.Fab")
			(hide yes)
			(effects
				(font
					(size 1 1)
					(thickness 0.15)
				)
			)
		)
		(property "Val" "100n"
			(at -44.176 292.186 0)
			(layer "F.Fab")
			(hide yes)
			(effects
				(font
					(size 1 1)
					(thickness 0.15)
				)
			)
		)
		(property "Voltage" ""
			(at -44.176 292.186 0)
			(layer "F.Fab")
			(hide yes)
			(effects
				(font
					(size 1 1)
					(thickness 0.15)
				)
			)
		)
		(sheetname "/PCIe-connector/")
		(sheetfile "pcie-conn.kicad_sch")
		(attr smd)
		(fp_rect
			(start -0.925 -0.47)
			(end 0.925 0.47)
			(stroke
				(width 0.05)
				(type default)
			)
			(fill no)
			(layer "F.CrtYd")
		)
		(fp_line
			(start -0.494 0.248)
			(end -0.494 -0.25)
			(stroke
				(width 0.15)
				(type solid)
			)
			(layer "F.Fab")
		)
		(fp_line
			(start 0.504 0.248)
			(end -0.494 0.248)
			(stroke
				(width 0.15)
				(type solid)
			)
			(layer "F.Fab")
		)
		(fp_line
			(start -0.494 -0.25)
			(end 0.504 -0.25)
			(stroke
				(width 0.15)
				(type solid)
			)
			(layer "F.Fab")
		)
		(fp_line
			(start 0.504 -0.25)
			(end 0.504 0.248)
			(stroke
				(width 0.15)
				(type solid)
			)
			(layer "F.Fab")
		)
		(pad "1" smd roundrect
			(at -0.48 0 270)
			(size 0.59 0.64)
			(layers "F.Cu" "F.Mask" "F.Paste")
			(roundrect_rratio 0.25)
			(net 371 "/PCIe-connector/PCIE_HPM_TX0_C_N")
			(pintype "passive")
		)
		(pad "2" smd roundrect
			(at 0.48 0 270)
			(size 0.59 0.64)
			(layers "F.Cu" "F.Mask" "F.Paste")
			(roundrect_rratio 0.25)
			(net 353 "PCIE_HPM_TX[0]_N")
			(pintype "passive")
		)
	)
	(footprint "antmicro-footprints:C_0402_1005Metric"
		(layer "F.Cu")
		(at 122.995 168.181 -90)
		(descr "Capacitor SMD 0402")
		(tags "capacitor SMD 0402")
		(property "Reference" "C27"
			(at 0.819 -0.404 90)
			(layer "F.SilkS")
			(effects
				(font
					(size 0.7 0.7)
					(thickness 0.15)
				)
				(justify right bottom)
			)
		)
		(property "Value" "C_100n_6V3_0402"
			(at 0 1.4 90)
			(layer "F.Fab")
			(effects
				(font
					(size 0.7 0.7)
					(thickness 0.15)
				)
				(justify right bottom)
			)
		)
		(property "Datasheet" "https://www.passivecomponent.com/wp-content/uploads/datasheet/WTC_MLCC_General_Purpose.pdf"
			(at 0 0 270)
			(layer "F.Fab")
			(hide yes)
			(effects
				(font
					(size 1.27 1.27)
					(thickness 0.15)
				)
			)
		)
		(property "Description" "SMT Multilayer Ceramic Capacitor, 0.1 µF, 6.3 V, 0402 [1005 Metric], ± 10%, X5R, Walsin MLCC"
			(at 0 0 270)
			(layer "F.Fab")
			(hide yes)
			(effects
				(font
					(size 1.27 1.27)
					(thickness 0.15)
				)
			)
		)
		(property "Author" "Antmicro"
			(at -45.186 291.176 0)
			(layer "F.Fab")
			(hide yes)
			(effects
				(font
					(size 1 1)
					(thickness 0.15)
				)
			)
		)
		(property "Dielectric" ""
			(at -45.186 291.176 0)
			(layer "F.Fab")
			(hide yes)
			(effects
				(font
					(size 1 1)
					(thickness 0.15)
				)
			)
		)
		(property "License" "Apache-2.0"
			(at -45.186 291.176 0)
			(layer "F.Fab")
			(hide yes)
			(effects
				(font
					(size 1 1)
					(thickness 0.15)
				)
			)
		)
		(property "MPN" "0402X104K6R3CT"
			(at -45.186 291.176 0)
			(layer "F.Fab")
			(hide yes)
			(effects
				(font
					(size 1 1)
					(thickness 0.15)
				)
			)
		)
		(property "Manufacturer" "Walsin"
			(at -45.186 291.176 0)
			(layer "F.Fab")
			(hide yes)
			(effects
				(font
					(size 1 1)
					(thickness 0.15)
				)
			)
		)
		(property "Public" "False"
			(at -45.186 291.176 0)
			(layer "F.Fab")
			(hide yes)
			(effects
				(font
					(size 1 1)
					(thickness 0.15)
				)
			)
		)
		(property "Val" "100n"
			(at -45.186 291.176 0)
			(layer "F.Fab")
			(hide yes)
			(effects
				(font
					(size 1 1)
					(thickness 0.15)
				)
			)
		)
		(property "Voltage" ""
			(at -45.186 291.176 0)
			(layer "F.Fab")
			(hide yes)
			(effects
				(font
					(size 1 1)
					(thickness 0.15)
				)
			)
		)
		(sheetname "/PCIe-connector/")
		(sheetfile "pcie-conn.kicad_sch")
		(attr smd)
		(fp_rect
			(start -0.925 -0.47)
			(end 0.925 0.47)
			(stroke
				(width 0.05)
				(type default)
			)
			(fill no)
			(layer "F.CrtYd")
		)
		(fp_line
			(start -0.494 0.248)
			(end -0.494 -0.25)
			(stroke
				(width 0.15)
				(type solid)
			)
			(layer "F.Fab")
		)
		(fp_line
			(start 0.504 0.248)
			(end -0.494 0.248)
			(stroke
				(width 0.15)
				(type solid)
			)
			(layer "F.Fab")
		)
		(fp_line
			(start -0.494 -0.25)
			(end 0.504 -0.25)
			(stroke
				(width 0.15)
				(type solid)
			)
			(layer "F.Fab")
		)
		(fp_line
			(start 0.504 -0.25)
			(end 0.504 0.248)
			(stroke
				(width 0.15)
				(type solid)
			)
			(layer "F.Fab")
		)
		(pad "1" smd roundrect
			(at -0.48 0 270)
			(size 0.59 0.64)
			(layers "F.Cu" "F.Mask" "F.Paste")
			(roundrect_rratio 0.25)
			(net 369 "/PCIe-connector/PCIE_HPM_TX0_C_P")
			(pintype "passive")
		)
		(pad "2" smd roundrect
			(at 0.48 0 270)
			(size 0.59 0.64)
			(layers "F.Cu" "F.Mask" "F.Paste")
			(roundrect_rratio 0.25)
			(net 351 "PCIE_HPM_TX[0]_P")
			(pintype "passive")
		)
	)
	(footprint "antmicro-footprints:C_0402_1005Metric"
		(layer "F.Cu")
		(at 85.8 78.025 180)
		(descr "Capacitor SMD 0402")
		(tags "capacitor SMD 0402")
		(property "Reference" "C89"
			(at -5.705 -0.675 0)
			(layer "F.SilkS")
			(effects
				(font
					(size 0.7 0.7)
					(thickness 0.15)
				)
				(justify right bottom)
			)
		)
		(property "Value" "C_10u_0402"
			(at 0 1.4 0)
			(layer "F.Fab")
			(effects
				(font
					(size 0.7 0.7)
					(thickness 0.15)
				)
				(justify right bottom)
			)
		)
		(property "Datasheet" "https://www.yageo.com/en/Chart/Download/pdf/CC0402MRX5R5BB106"
			(at 0 0 180)
			(layer "F.Fab")
			(hide yes)
			(effects
				(font
					(size 1.27 1.27)
					(thickness 0.15)
				)
			)
		)
		(property "Description" "SMD Multilayer Ceramic Capacitor, 10 µF, 6.3 V, 0402 [1005 Metric], ± 20%, X5R, CC Series"
			(at 0 0 180)
			(layer "F.Fab")
			(hide yes)
			(effects
				(font
					(size 1.27 1.27)
					(thickness 0.15)
				)
			)
		)
		(property "Author" "Antmicro"
			(at 171.6 156.05 0)
			(layer "F.Fab")
			(hide yes)
			(effects
				(font
					(size 1 1)
					(thickness 0.15)
				)
			)
		)
		(property "Dielectric" ""
			(at 171.6 156.05 0)
			(layer "F.Fab")
			(hide yes)
			(effects
				(font
					(size 1 1)
					(thickness 0.15)
				)
			)
		)
		(property "License" "Apache-2.0"
			(at 171.6 156.05 0)
			(layer "F.Fab")
			(hide yes)
			(effects
				(font
					(size 1 1)
					(thickness 0.15)
				)
			)
		)
		(property "MPN" "CC0402MRX5R5BB106"
			(at 171.6 156.05 0)
			(layer "F.Fab")
			(hide yes)
			(effects
				(font
					(size 1 1)
					(thickness 0.15)
				)
			)
		)
		(property "Manufacturer" "YAGEO"
			(at 171.6 156.05 0)
			(layer "F.Fab")
			(hide yes)
			(effects
				(font
					(size 1 1)
					(thickness 0.15)
				)
			)
		)
		(property "Val" "10u"
			(at 171.6 156.05 0)
			(layer "F.Fab")
			(hide yes)
			(effects
				(font
					(size 1 1)
					(thickness 0.15)
				)
			)
		)
		(property "Voltage" ""
			(at 171.6 156.05 0)
			(layer "F.Fab")
			(hide yes)
			(effects
				(font
					(size 1 1)
					(thickness 0.15)
				)
			)
		)
		(sheetname "/Power supply/")
		(sheetfile "power-supply.kicad_sch")
		(attr smd)
		(fp_rect
			(start -0.925 -0.47)
			(end 0.925 0.47)
			(stroke
				(width 0.05)
				(type default)
			)
			(fill no)
			(layer "F.CrtYd")
		)
		(fp_line
			(start 0.504 0.248)
			(end -0.494 0.248)
			(stroke
				(width 0.15)
				(type solid)
			)
			(layer "F.Fab")
		)
		(fp_line
			(start 0.504 -0.25)
			(end 0.504 0.248)
			(stroke
				(width 0.15)
				(type solid)
			)
			(layer "F.Fab")
		)
		(fp_line
			(start -0.494 0.248)
			(end -0.494 -0.25)
			(stroke
				(width 0.15)
				(type solid)
			)
			(layer "F.Fab")
		)
		(fp_line
			(start -0.494 -0.25)
			(end 0.504 -0.25)
			(stroke
				(width 0.15)
				(type solid)
			)
			(layer "F.Fab")
		)
		(pad "1" smd roundrect
			(at -0.48 0 180)
			(size 0.59 0.64)
			(layers "F.Cu" "F.Mask" "F.Paste")
			(roundrect_rratio 0.25)
			(net 1 "GND")
			(pintype "passive")
		)
		(pad "2" smd roundrect
			(at 0.48 0 180)
			(size 0.59 0.64)
			(layers "F.Cu" "F.Mask" "F.Paste")
			(roundrect_rratio 0.25)
			(net 276 "Net-(C81-Pad2)")
			(pintype "passive")
		)
	)
	(footprint "antmicro-footprints:C_0402_1005Metric"
		(layer "F.Cu")
		(at 85.905 86.835 180)
		(descr "Capacitor SMD 0402")
		(tags "capacitor SMD 0402")
		(property "Reference" "C86"
			(at -2.995 -0.315 0)
			(layer "F.SilkS")
			(effects
				(font
					(size 0.7 0.7)
					(thickness 0.15)
				)
				(justify right bottom)
			)
		)
		(property "Value" "C_10u_0402"
			(at 0 1.4 0)
			(layer "F.Fab")
			(effects
				(font
					(size 0.7 0.7)
					(thickness 0.15)
				)
				(justify right bottom)
			)
		)
		(property "Datasheet" "https://www.yageo.com/en/Chart/Download/pdf/CC0402MRX5R5BB106"
			(at 0 0 180)
			(layer "F.Fab")
			(hide yes)
			(effects
				(font
					(size 1.27 1.27)
					(thickness 0.15)
				)
			)
		)
		(property "Description" "SMD Multilayer Ceramic Capacitor, 10 µF, 6.3 V, 0402 [1005 Metric], ± 20%, X5R, CC Series"
			(at 0 0 180)
			(layer "F.Fab")
			(hide yes)
			(effects
				(font
					(size 1.27 1.27)
					(thickness 0.15)
				)
			)
		)
		(property "Author" "Antmicro"
			(at 171.81 173.67 0)
			(layer "F.Fab")
			(hide yes)
			(effects
				(font
					(size 1 1)
					(thickness 0.15)
				)
			)
		)
		(property "Dielectric" ""
			(at 171.81 173.67 0)
			(layer "F.Fab")
			(hide yes)
			(effects
				(font
					(size 1 1)
					(thickness 0.15)
				)
			)
		)
		(property "License" "Apache-2.0"
			(at 171.81 173.67 0)
			(layer "F.Fab")
			(hide yes)
			(effects
				(font
					(size 1 1)
					(thickness 0.15)
				)
			)
		)
		(property "MPN" "CC0402MRX5R5BB106"
			(at 171.81 173.67 0)
			(layer "F.Fab")
			(hide yes)
			(effects
				(font
					(size 1 1)
					(thickness 0.15)
				)
			)
		)
		(property "Manufacturer" "YAGEO"
			(at 171.81 173.67 0)
			(layer "F.Fab")
			(hide yes)
			(effects
				(font
					(size 1 1)
					(thickness 0.15)
				)
			)
		)
		(property "Val" "10u"
			(at 171.81 173.67 0)
			(layer "F.Fab")
			(hide yes)
			(effects
				(font
					(size 1 1)
					(thickness 0.15)
				)
			)
		)
		(property "Voltage" ""
			(at 171.81 173.67 0)
			(layer "F.Fab")
			(hide yes)
			(effects
				(font
					(size 1 1)
					(thickness 0.15)
				)
			)
		)
		(sheetname "/Power supply/")
		(sheetfile "power-supply.kicad_sch")
		(attr smd)
		(fp_rect
			(start -0.925 -0.47)
			(end 0.925 0.47)
			(stroke
				(width 0.05)
				(type default)
			)
			(fill no)
			(layer "F.CrtYd")
		)
		(fp_line
			(start 0.504 0.248)
			(end -0.494 0.248)
			(stroke
				(width 0.15)
				(type solid)
			)
			(layer "F.Fab")
		)
		(fp_line
			(start 0.504 -0.25)
			(end 0.504 0.248)
			(stroke
				(width 0.15)
				(type solid)
			)
			(layer "F.Fab")
		)
		(fp_line
			(start -0.494 0.248)
			(end -0.494 -0.25)
			(stroke
				(width 0.15)
				(type solid)
			)
			(layer "F.Fab")
		)
		(fp_line
			(start -0.494 -0.25)
			(end 0.504 -0.25)
			(stroke
				(width 0.15)
				(type solid)
			)
			(layer "F.Fab")
		)
		(pad "1" smd roundrect
			(at -0.48 0 180)
			(size 0.59 0.64)
			(layers "F.Cu" "F.Mask" "F.Paste")
			(roundrect_rratio 0.25)
			(net 1 "GND")
			(pintype "passive")
		)
		(pad "2" smd roundrect
			(at 0.48 0 180)
			(size 0.59 0.64)
			(layers "F.Cu" "F.Mask" "F.Paste")
			(roundrect_rratio 0.25)
			(net 277 "Net-(C82-Pad2)")
			(pintype "passive")
		)
	)
)
